(kicad_pcb
	(version 20260206)
	(generator "pcbnew")
	(generator_version "10.0")
	(general
		(thickness 1.6)
		(legacy_teardrops no)
	)
	(paper "A4")
	(title_block
		(title "Bryce Canyon_SCC_16316-1_OCP.brd")
		(comment 1 "Bryce Canyon / footprints 928-935 of 1561")
	)
	(layers
		(0 "F.Cu" signal "TOP")
		(4 "In1.Cu" signal "L2GND")
		(6 "In2.Cu" signal "L3")
		(8 "In3.Cu" signal "L4VCC")
		(10 "In4.Cu" signal "L5VCC")
		(12 "In5.Cu" signal "L6")
		(14 "In6.Cu" signal "L7GND")
		(2 "B.Cu" signal "BOTTOM")
		(9 "F.Adhes" user "F.Adhesive")
		(11 "B.Adhes" user "B.Adhesive")
		(13 "F.Paste" user "Package Geometry/Pastemask Top")
		(15 "B.Paste" user "Package Geometry/Pastemask Bottom")
		(5 "F.SilkS" user "Ref Des/Silkscreen Top")
		(7 "B.SilkS" user "Ref Des/Silkscreen Bottom")
		(1 "F.Mask" user "Board Geometry/Soldermask Top")
		(3 "B.Mask" user "Board Geometry/Soldermask Bottom")
		(17 "Dwgs.User" user "User.Drawings")
		(19 "Cmts.User" user "User.Comments")
		(21 "Eco1.User" user "User.Eco1")
		(23 "Eco2.User" user "User.Eco2")
		(25 "Edge.Cuts" user "Board Geometry/Outline")
		(27 "Margin" user)
		(31 "F.CrtYd" user "Package Geometry/Place Bound Top")
		(29 "B.CrtYd" user "Package Geometry/Place Bound Bottom")
		(35 "F.Fab" user "Ref Des/Assembly Top")
		(33 "B.Fab" user "Ref Des/Assembly Bottom")
	)
	(footprint ""
		(layer "B.Cu")
		(at 117.6782 -71.9074)
		(property "Reference" "C140"
			(at 0 0 0)
			(layer "B.SilkS")
			(hide yes)
			(effects
				(font
					(size 1.27 1.27)
				)
				(justify mirror)
			)
		)
		(property "Value" "SCD1U6D3V1KX-GP"
			(at 2.8321 -1.7399 0)
			(unlocked yes)
			(layer "B.Fab")
			(hide yes)
			(effects
				(font
					(size 1.016 1.016)
					(thickness 0.1524)
				)
				(justify mirror)
			)
		)
		(property "Device Type" "C0201H13"
			(at 2.8321 -3.2639 0)
			(unlocked yes)
			(layer "B.Fab")
			(hide yes)
			(effects
				(font
					(size 1.016 1.016)
					(thickness 0.1524)
				)
				(justify mirror)
			)
		)
		(duplicate_pad_numbers_are_jumpers no)
		(fp_rect
			(start 0.2794 0.6477)
			(end -0.2794 -0.6477)
			(stroke
				(width 0)
				(type default)
			)
			(fill no)
			(layer "B.CrtYd")
		)
		(fp_rect
			(start 0.2794 0.6477)
			(end -0.2794 -0.6477)
			(stroke
				(width 0)
				(type default)
			)
			(fill no)
			(layer "B.Fab")
		)
		(pad "1" smd custom
			(at 0 -0.2794 180)
			(size 0.0762 0.0762)
			(layers "B.Cu" "B.Mask" "B.Paste")
			(net "P1V8_E")
			(options
				(clearance outline)
				(anchor circle)
			)
			(primitives
				(gr_poly
					(pts
						(arc
							(start 0.1524 0.127)
							(mid 0.137521 0.162921)
							(end 0.1016 0.1778)
						)
						(arc
							(start -0.1016 0.1778)
							(mid -0.137521 0.162921)
							(end -0.1524 0.127)
						)
						(arc
							(start -0.1524 -0.127)
							(mid -0.137521 -0.162921)
							(end -0.1016 -0.1778)
						)
						(arc
							(start 0.1016 -0.1778)
							(mid 0.137521 -0.162921)
							(end 0.1524 -0.127)
						)
					)
					(width 0)
					(fill yes)
				)
			)
		)
		(pad "2" smd custom
			(at 0 0.2794 180)
			(size 0.0762 0.0762)
			(layers "B.Cu" "B.Mask" "B.Paste")
			(net "GND")
			(options
				(clearance outline)
				(anchor circle)
			)
			(primitives
				(gr_poly
					(pts
						(arc
							(start 0.1524 0.127)
							(mid 0.137521 0.162921)
							(end 0.1016 0.1778)
						)
						(arc
							(start -0.1016 0.1778)
							(mid -0.137521 0.162921)
							(end -0.1524 0.127)
						)
						(arc
							(start -0.1524 -0.127)
							(mid -0.137521 -0.162921)
							(end -0.1016 -0.1778)
						)
						(arc
							(start 0.1016 -0.1778)
							(mid 0.137521 -0.162921)
							(end 0.1524 -0.127)
						)
					)
					(width 0)
					(fill yes)
				)
			)
		)
	)
	(footprint ""
		(layer "B.Cu")
		(at 147.701 -117.348)
		(property "Reference" "R381"
			(at 0 0 0)
			(layer "B.SilkS")
			(hide yes)
			(effects
				(font
					(size 1.27 1.27)
				)
				(justify mirror)
			)
		)
		(property "Value" "2D2R3-1-U-GP"
			(at 0.0254 -2.5146 0)
			(unlocked yes)
			(layer "B.Fab")
			(hide yes)
			(effects
				(font
					(size 1.016 1.016)
					(thickness 0.1524)
				)
				(justify mirror)
			)
		)
		(property "Device Type" "R603H22"
			(at 0.0254 -4.0386 0)
			(unlocked yes)
			(layer "B.Fab")
			(hide yes)
			(effects
				(font
					(size 1.016 1.016)
					(thickness 0.1524)
				)
				(justify mirror)
			)
		)
		(duplicate_pad_numbers_are_jumpers no)
		(fp_line
			(start -0.2032 0)
			(end -0.4826 0)
			(stroke
				(width 0.2032)
				(type default)
			)
			(layer "B.SilkS")
		)
		(fp_line
			(start 0.4826 0)
			(end 0.2032 0)
			(stroke
				(width 0.2032)
				(type default)
			)
			(layer "B.SilkS")
		)
		(fp_rect
			(start 0.5842 1.3335)
			(end -0.5842 -1.3335)
			(stroke
				(width 0)
				(type default)
			)
			(fill no)
			(layer "B.CrtYd")
		)
		(fp_rect
			(start 0.5842 1.3335)
			(end -0.5842 -1.3335)
			(stroke
				(width 0)
				(type default)
			)
			(fill no)
			(layer "B.Fab")
		)
		(pad "1" smd custom
			(at 0 -0.762 180)
			(size 0.2159 0.2159)
			(layers "B.Cu" "B.Mask" "B.Paste")
			(net "P1V5_E_VBST")
			(options
				(clearance outline)
				(anchor circle)
			)
			(primitives
				(gr_poly
					(pts
						(arc
							(start -0.3302 0.4318)
							(mid -0.402042 0.402042)
							(end -0.4318 0.3302)
						)
						(arc
							(start -0.4318 -0.3302)
							(mid -0.402042 -0.402042)
							(end -0.3302 -0.4318)
						)
						(arc
							(start 0.3302 -0.4318)
							(mid 0.402042 -0.402042)
							(end 0.4318 -0.3302)
						)
						(arc
							(start 0.4318 0.3302)
							(mid 0.402042 0.402042)
							(end 0.3302 0.4318)
						)
					)
					(width 0)
					(fill yes)
				)
			)
		)
		(pad "2" smd custom
			(at 0 0.762 180)
			(size 0.2159 0.2159)
			(layers "B.Cu" "B.Mask" "B.Paste")
			(net "P1V5_E_RC")
			(options
				(clearance outline)
				(anchor circle)
			)
			(primitives
				(gr_poly
					(pts
						(arc
							(start -0.3302 0.4318)
							(mid -0.402042 0.402042)
							(end -0.4318 0.3302)
						)
						(arc
							(start -0.4318 -0.3302)
							(mid -0.402042 -0.402042)
							(end -0.3302 -0.4318)
						)
						(arc
							(start 0.3302 -0.4318)
							(mid 0.402042 -0.402042)
							(end 0.4318 -0.3302)
						)
						(arc
							(start 0.4318 0.3302)
							(mid 0.402042 0.402042)
							(end 0.3302 0.4318)
						)
					)
					(width 0)
					(fill yes)
				)
			)
		)
	)
	(footprint ""
		(layer "B.Cu")
		(at 186.309 -37.084 90)
		(property "Reference" "TP100"
			(at 0 0 90)
			(layer "B.SilkS")
			(hide yes)
			(effects
				(font
					(size 1.27 1.27)
				)
				(justify mirror)
			)
		)
		(property "Value" "TPAD28-2-GP"
			(at 0.0127 -1.6637 90)
			(unlocked yes)
			(layer "B.Fab")
			(hide yes)
			(effects
				(font
					(size 1.016 1.016)
					(thickness 0.1524)
				)
				(justify mirror)
			)
		)
		(property "Device Type" "TPAD28"
			(at 0.0127 -3.1877 90)
			(unlocked yes)
			(layer "B.Fab")
			(hide yes)
			(effects
				(font
					(size 1.016 1.016)
					(thickness 0.1524)
				)
				(justify mirror)
			)
		)
		(duplicate_pad_numbers_are_jumpers no)
		(fp_poly
			(pts
				(arc
					(start 0 0.3556)
					(mid 0 -0.3556)
					(end 0 0.3556)
				)
			)
			(stroke
				(width 0)
				(type default)
			)
			(fill no)
			(layer "B.CrtYd")
		)
		(fp_poly
			(pts
				(arc
					(start 0 0.6096)
					(mid 0 -0.6096)
					(end 0 0.6096)
				)
			)
			(stroke
				(width 0)
				(type default)
			)
			(fill no)
			(layer "B.Fab")
		)
		(pad "1" smd circle
			(at 0 0 270)
			(size 0.7112 0.7112)
			(layers "B.Cu" "B.Mask" "B.Paste")
			(net "IOC_GPIO_38")
		)
	)
	(footprint ""
		(layer "B.Cu")
		(at 160.528 -52.07)
		(property "Reference" "R200"
			(at 0 0 0)
			(layer "B.SilkS")
			(hide yes)
			(effects
				(font
					(size 1.27 1.27)
				)
				(justify mirror)
			)
		)
		(property "Value" "2K2R2F-GP"
			(at -0.064008 -3.993896 0)
			(unlocked yes)
			(layer "B.Fab")
			(hide yes)
			(effects
				(font
					(size 1.016 1.016)
					(thickness 0.1524)
				)
				(justify mirror)
			)
		)
		(property "Device Type" "R402H16"
			(at -0.064008 -5.517896 0)
			(unlocked yes)
			(layer "B.Fab")
			(hide yes)
			(effects
				(font
					(size 1.016 1.016)
					(thickness 0.1524)
				)
				(justify mirror)
			)
		)
		(duplicate_pad_numbers_are_jumpers no)
		(fp_line
			(start -0.508 -0.9398)
			(end 0.508 -0.9398)
			(stroke
				(width 0.1524)
				(type default)
			)
			(layer "B.SilkS")
		)
		(fp_line
			(start 0.508 -0.9398)
			(end 0.508 0.9398)
			(stroke
				(width 0.1524)
				(type default)
			)
			(layer "B.SilkS")
		)
		(fp_rect
			(start 0.508 0.9398)
			(end -0.508 -0.9398)
			(stroke
				(width 0)
				(type default)
			)
			(fill no)
			(layer "B.CrtYd")
		)
		(fp_rect
			(start 0.508 0.9398)
			(end -0.508 -0.9398)
			(stroke
				(width 0)
				(type default)
			)
			(fill no)
			(layer "B.Fab")
		)
		(pad "1" smd custom
			(at 0 -0.4445 180)
			(size 0.1397 0.1397)
			(layers "B.Cu" "B.Mask" "B.Paste")
			(net "P1V8_C")
			(options
				(clearance outline)
				(anchor circle)
			)
			(primitives
				(gr_poly
					(pts
						(arc
							(start -0.1778 0.2794)
							(mid -0.249642 0.249642)
							(end -0.2794 0.1778)
						)
						(arc
							(start -0.2794 -0.1778)
							(mid -0.249642 -0.249642)
							(end -0.1778 -0.2794)
						)
						(arc
							(start 0.1778 -0.2794)
							(mid 0.249642 -0.249642)
							(end 0.2794 -0.1778)
						)
						(arc
							(start 0.2794 0.1778)
							(mid 0.249642 0.249642)
							(end 0.1778 0.2794)
						)
					)
					(width 0)
					(fill yes)
				)
			)
		)
		(pad "2" smd custom
			(at 0 0.4445 180)
			(size 0.1397 0.1397)
			(layers "B.Cu" "B.Mask" "B.Paste")
			(net "SIO_CLK_1")
			(options
				(clearance outline)
				(anchor circle)
			)
			(primitives
				(gr_poly
					(pts
						(arc
							(start -0.1778 0.2794)
							(mid -0.249642 0.249642)
							(end -0.2794 0.1778)
						)
						(arc
							(start -0.2794 -0.1778)
							(mid -0.249642 -0.249642)
							(end -0.1778 -0.2794)
						)
						(arc
							(start 0.1778 -0.2794)
							(mid 0.249642 -0.249642)
							(end 0.2794 -0.1778)
						)
						(arc
							(start 0.2794 0.1778)
							(mid 0.249642 0.249642)
							(end 0.1778 0.2794)
						)
					)
					(width 0)
					(fill yes)
				)
			)
		)
	)
	(footprint ""
		(layer "B.Cu")
		(at 182.245 -34.7853)
		(property "Reference" "R257"
			(at 0 0 0)
			(layer "B.SilkS")
			(hide yes)
			(effects
				(font
					(size 1.27 1.27)
				)
				(justify mirror)
			)
		)
		(property "Value" "10KR2F-2-GP"
			(at -0.064008 -3.993896 0)
			(unlocked yes)
			(layer "B.Fab")
			(hide yes)
			(effects
				(font
					(size 1.016 1.016)
					(thickness 0.1524)
				)
				(justify mirror)
			)
		)
		(property "Device Type" "R402H16"
			(at -0.064008 -5.517896 0)
			(unlocked yes)
			(layer "B.Fab")
			(hide yes)
			(effects
				(font
					(size 1.016 1.016)
					(thickness 0.1524)
				)
				(justify mirror)
			)
		)
		(duplicate_pad_numbers_are_jumpers no)
		(fp_line
			(start -0.508 -0.9398)
			(end 0.508 -0.9398)
			(stroke
				(width 0.1524)
				(type default)
			)
			(layer "B.SilkS")
		)
		(fp_line
			(start 0.508 -0.9398)
			(end 0.508 0.9398)
			(stroke
				(width 0.1524)
				(type default)
			)
			(layer "B.SilkS")
		)
		(fp_rect
			(start 0.508 0.9398)
			(end -0.508 -0.9398)
			(stroke
				(width 0)
				(type default)
			)
			(fill no)
			(layer "B.CrtYd")
		)
		(fp_rect
			(start 0.508 0.9398)
			(end -0.508 -0.9398)
			(stroke
				(width 0)
				(type default)
			)
			(fill no)
			(layer "B.Fab")
		)
		(pad "1" smd custom
			(at 0 -0.4445 180)
			(size 0.1397 0.1397)
			(layers "B.Cu" "B.Mask" "B.Paste")
			(net "P1V8_C")
			(options
				(clearance outline)
				(anchor circle)
			)
			(primitives
				(gr_poly
					(pts
						(arc
							(start -0.1778 0.2794)
							(mid -0.249642 0.249642)
							(end -0.2794 0.1778)
						)
						(arc
							(start -0.2794 -0.1778)
							(mid -0.249642 -0.249642)
							(end -0.1778 -0.2794)
						)
						(arc
							(start 0.1778 -0.2794)
							(mid 0.249642 -0.249642)
							(end 0.2794 -0.1778)
						)
						(arc
							(start 0.2794 0.1778)
							(mid 0.249642 0.249642)
							(end 0.1778 0.2794)
						)
					)
					(width 0)
					(fill yes)
				)
			)
		)
		(pad "2" smd custom
			(at 0 0.4445 180)
			(size 0.1397 0.1397)
			(layers "B.Cu" "B.Mask" "B.Paste")
			(net "SYS_RST_N_1")
			(options
				(clearance outline)
				(anchor circle)
			)
			(primitives
				(gr_poly
					(pts
						(arc
							(start -0.1778 0.2794)
							(mid -0.249642 0.249642)
							(end -0.2794 0.1778)
						)
						(arc
							(start -0.2794 -0.1778)
							(mid -0.249642 -0.249642)
							(end -0.1778 -0.2794)
						)
						(arc
							(start 0.1778 -0.2794)
							(mid 0.249642 -0.249642)
							(end 0.2794 -0.1778)
						)
						(arc
							(start 0.2794 0.1778)
							(mid 0.249642 0.249642)
							(end 0.1778 0.2794)
						)
					)
					(width 0)
					(fill yes)
				)
			)
		)
	)
	(footprint ""
		(layer "B.Cu")
		(at 182.245 -31.75 -90)
		(property "Reference" "C468"
			(at 0 0 90)
			(layer "B.SilkS")
			(hide yes)
			(effects
				(font
					(size 1.27 1.27)
				)
				(justify mirror)
			)
		)
		(property "Value" "SCD1U6D3V1KX-GP"
			(at 2.8321 -1.7399 270)
			(unlocked yes)
			(layer "B.Fab")
			(hide yes)
			(effects
				(font
					(size 1.016 1.016)
					(thickness 0.1524)
				)
				(justify mirror)
			)
		)
		(property "Device Type" "C0201H13"
			(at 2.8321 -3.2639 270)
			(unlocked yes)
			(layer "B.Fab")
			(hide yes)
			(effects
				(font
					(size 1.016 1.016)
					(thickness 0.1524)
				)
				(justify mirror)
			)
		)
		(duplicate_pad_numbers_are_jumpers no)
		(fp_rect
			(start 0.2794 0.6477)
			(end -0.2794 -0.6477)
			(stroke
				(width 0)
				(type default)
			)
			(fill no)
			(layer "B.CrtYd")
		)
		(fp_rect
			(start 0.2794 0.6477)
			(end -0.2794 -0.6477)
			(stroke
				(width 0)
				(type default)
			)
			(fill no)
			(layer "B.Fab")
		)
		(pad "1" smd custom
			(at 0 -0.2794 90)
			(size 0.0762 0.0762)
			(layers "B.Cu" "B.Mask" "B.Paste")
			(net "P1V8_C")
			(options
				(clearance outline)
				(anchor circle)
			)
			(primitives
				(gr_poly
					(pts
						(arc
							(start 0.1524 0.127)
							(mid 0.137521 0.162921)
							(end 0.1016 0.1778)
						)
						(arc
							(start -0.1016 0.1778)
							(mid -0.137521 0.162921)
							(end -0.1524 0.127)
						)
						(arc
							(start -0.1524 -0.127)
							(mid -0.137521 -0.162921)
							(end -0.1016 -0.1778)
						)
						(arc
							(start 0.1016 -0.1778)
							(mid 0.137521 -0.162921)
							(end 0.1524 -0.127)
						)
					)
					(width 0)
					(fill yes)
				)
			)
		)
		(pad "2" smd custom
			(at 0 0.2794 90)
			(size 0.0762 0.0762)
			(layers "B.Cu" "B.Mask" "B.Paste")
			(net "GND")
			(options
				(clearance outline)
				(anchor circle)
			)
			(primitives
				(gr_poly
					(pts
						(arc
							(start 0.1524 0.127)
							(mid 0.137521 0.162921)
							(end 0.1016 0.1778)
						)
						(arc
							(start -0.1016 0.1778)
							(mid -0.137521 0.162921)
							(end -0.1524 0.127)
						)
						(arc
							(start -0.1524 -0.127)
							(mid -0.137521 -0.162921)
							(end -0.1016 -0.1778)
						)
						(arc
							(start 0.1016 -0.1778)
							(mid 0.137521 -0.162921)
							(end 0.1524 -0.127)
						)
					)
					(width 0)
					(fill yes)
				)
			)
		)
	)
	(footprint ""
		(layer "B.Cu")
		(at 170.923204 -20.88642)
		(property "Reference" "C317"
			(at 0 0 0)
			(layer "B.SilkS")
			(hide yes)
			(effects
				(font
					(size 1.27 1.27)
				)
				(justify mirror)
			)
		)
		(property "Value" "SCD22U10V1KX-GP"
			(at 2.8321 -1.7399 0)
			(unlocked yes)
			(layer "B.Fab")
			(hide yes)
			(effects
				(font
					(size 1.016 1.016)
					(thickness 0.1524)
				)
				(justify mirror)
			)
		)
		(property "Device Type" "C0201H13"
			(at 2.8321 -3.2639 0)
			(unlocked yes)
			(layer "B.Fab")
			(hide yes)
			(effects
				(font
					(size 1.016 1.016)
					(thickness 0.1524)
				)
				(justify mirror)
			)
		)
		(duplicate_pad_numbers_are_jumpers no)
		(fp_rect
			(start 0.2794 0.6477)
			(end -0.2794 -0.6477)
			(stroke
				(width 0)
				(type default)
			)
			(fill no)
			(layer "B.CrtYd")
		)
		(fp_rect
			(start 0.2794 0.6477)
			(end -0.2794 -0.6477)
			(stroke
				(width 0)
				(type default)
			)
			(fill no)
			(layer "B.Fab")
		)
		(pad "1" smd custom
			(at 0 -0.2794 180)
			(size 0.0762 0.0762)
			(layers "B.Cu" "B.Mask" "B.Paste")
			(net "PCIE_SCC_TO_COMP_C_3_DP")
			(options
				(clearance outline)
				(anchor circle)
			)
			(primitives
				(gr_poly
					(pts
						(arc
							(start 0.1524 0.127)
							(mid 0.137521 0.162921)
							(end 0.1016 0.1778)
						)
						(arc
							(start -0.1016 0.1778)
							(mid -0.137521 0.162921)
							(end -0.1524 0.127)
						)
						(arc
							(start -0.1524 -0.127)
							(mid -0.137521 -0.162921)
							(end -0.1016 -0.1778)
						)
						(arc
							(start 0.1016 -0.1778)
							(mid 0.137521 -0.162921)
							(end 0.1524 -0.127)
						)
					)
					(width 0)
					(fill yes)
				)
			)
		)
		(pad "2" smd custom
			(at 0 0.2794 180)
			(size 0.0762 0.0762)
			(layers "B.Cu" "B.Mask" "B.Paste")
			(net "PCIE_SCC_TO_COMP_3_DP")
			(options
				(clearance outline)
				(anchor circle)
			)
			(primitives
				(gr_poly
					(pts
						(arc
							(start 0.1524 0.127)
							(mid 0.137521 0.162921)
							(end 0.1016 0.1778)
						)
						(arc
							(start -0.1016 0.1778)
							(mid -0.137521 0.162921)
							(end -0.1524 0.127)
						)
						(arc
							(start -0.1524 -0.127)
							(mid -0.137521 -0.162921)
							(end -0.1016 -0.1778)
						)
						(arc
							(start 0.1016 -0.1778)
							(mid 0.137521 -0.162921)
							(end 0.1524 -0.127)
						)
					)
					(width 0)
					(fill yes)
				)
			)
		)
	)
	(footprint ""
		(layer "B.Cu")
		(at 183.144668 -43.19651 -90)
		(property "Reference" "C478"
			(at 0 0 90)
			(layer "B.SilkS")
			(hide yes)
			(effects
				(font
					(size 1.27 1.27)
				)
				(justify mirror)
			)
		)
		(property "Value" "SCD1U6D3V1KX-GP"
			(at 2.8321 -1.7399 270)
			(unlocked yes)
			(layer "B.Fab")
			(hide yes)
			(effects
				(font
					(size 1.016 1.016)
					(thickness 0.1524)
				)
				(justify mirror)
			)
		)
		(property "Device Type" "C0201H13"
			(at 2.8321 -3.2639 270)
			(unlocked yes)
			(layer "B.Fab")
			(hide yes)
			(effects
				(font
					(size 1.016 1.016)
					(thickness 0.1524)
				)
				(justify mirror)
			)
		)
		(duplicate_pad_numbers_are_jumpers no)
		(fp_rect
			(start 0.2794 0.6477)
			(end -0.2794 -0.6477)
			(stroke
				(width 0)
				(type default)
			)
			(fill no)
			(layer "B.CrtYd")
		)
		(fp_rect
			(start 0.2794 0.6477)
			(end -0.2794 -0.6477)
			(stroke
				(width 0)
				(type default)
			)
			(fill no)
			(layer "B.Fab")
		)
		(pad "1" smd custom
			(at 0 -0.2794 90)
			(size 0.0762 0.0762)
			(layers "B.Cu" "B.Mask" "B.Paste")
			(net "P1V8_C")
			(options
				(clearance outline)
				(anchor circle)
			)
			(primitives
				(gr_poly
					(pts
						(arc
							(start 0.1524 0.127)
							(mid 0.137521 0.162921)
							(end 0.1016 0.1778)
						)
						(arc
							(start -0.1016 0.1778)
							(mid -0.137521 0.162921)
							(end -0.1524 0.127)
						)
						(arc
							(start -0.1524 -0.127)
							(mid -0.137521 -0.162921)
							(end -0.1016 -0.1778)
						)
						(arc
							(start 0.1016 -0.1778)
							(mid 0.137521 -0.162921)
							(end 0.1524 -0.127)
						)
					)
					(width 0)
					(fill yes)
				)
			)
		)
		(pad "2" smd custom
			(at 0 0.2794 90)
			(size 0.0762 0.0762)
			(layers "B.Cu" "B.Mask" "B.Paste")
			(net "GND")
			(options
				(clearance outline)
				(anchor circle)
			)
			(primitives
				(gr_poly
					(pts
						(arc
							(start 0.1524 0.127)
							(mid 0.137521 0.162921)
							(end 0.1016 0.1778)
						)
						(arc
							(start -0.1016 0.1778)
							(mid -0.137521 0.162921)
							(end -0.1524 0.127)
						)
						(arc
							(start -0.1524 -0.127)
							(mid -0.137521 -0.162921)
							(end -0.1016 -0.1778)
						)
						(arc
							(start 0.1016 -0.1778)
							(mid 0.137521 -0.162921)
							(end 0.1524 -0.127)
						)
					)
					(width 0)
					(fill yes)
				)
			)
		)
	)
)
